# T6G (Grand Teton) — schematic netlist excerpt (pin names and nets, part order shuffled) for the footprints in the layout excerpt that follows; sources: Cadence DE-HDL packaged netlist, KiCad conversion of 04192023_DAF0TMB3IC0_F0TG_MB_C_brd_V02_OCP.brd

PR4012  Q_RES  0 5% CHIP  pkg 0402LF  page 152 : A = P12V_SCM_PWRGD ; B = HP_LVC3_SCM_HSC_PWRGD
R6012  Q_RES  0 5% CHIP  pkg 0402LF  page 150 : A = SGPIO_SCM_DO_<1> ; B = SGPIO_SCM_DO_R_<1>

(kicad_pcb
	(version 20260206)
	(generator "pcbnew")
	(generator_version "10.0")
	(general
		(thickness 1.6)
		(legacy_teardrops no)
	)
	(paper "A4")
	(title_block
		(title "04192023_DAF0TMB3IC0_F0TG_MB_C_brd_V02_OCP.brd")
		(comment 1 "Grand Teton / footprints 1765-1766 of 8354")
	)
	(layers
		(0 "F.Cu" signal "TOP")
		(4 "In1.Cu" signal "GND")
		(6 "In2.Cu" signal "IN1")
		(8 "In3.Cu" signal "GND1")
		(10 "In4.Cu" signal "IN2")
		(12 "In5.Cu" signal "GND2")
		(14 "In6.Cu" signal "IN3")
		(16 "In7.Cu" signal "GND3")
		(18 "In8.Cu" signal "VCC")
		(20 "In9.Cu" signal "VCC1")
		(22 "In10.Cu" signal "GND4")
		(24 "In11.Cu" signal "IN4")
		(26 "In12.Cu" signal "GND5")
		(28 "In13.Cu" signal "IN5")
		(30 "In14.Cu" signal "GND6")
		(32 "In15.Cu" signal "IN6")
		(34 "In16.Cu" signal "GND7")
		(2 "B.Cu" signal "BOTTOM")
		(9 "F.Adhes" user "F.Adhesive")
		(11 "B.Adhes" user "B.Adhesive")
		(13 "F.Paste" user "Package Geometry/Pastemask Top")
		(15 "B.Paste" user "Package Geometry/Pastemask Bottom")
		(5 "F.SilkS" user "Ref Des/Silkscreen Top")
		(7 "B.SilkS" user "Ref Des/Silkscreen Bottom")
		(1 "F.Mask" user "Board Geometry/Soldermask Top")
		(3 "B.Mask" user "Board Geometry/Soldermask Bottom")
		(17 "Dwgs.User" user "User.Drawings")
		(19 "Cmts.User" user "User.Comments")
		(21 "Eco1.User" user "User.Eco1")
		(23 "Eco2.User" user "User.Eco2")
		(25 "Edge.Cuts" user "Board Geometry/Outline")
		(27 "Margin" user)
		(31 "F.CrtYd" user "Package Geometry/Place Bound Top")
		(29 "B.CrtYd" user "Package Geometry/Place Bound Bottom")
		(35 "F.Fab" user "Ref Des/Assembly Top")
		(33 "B.Fab" user "Ref Des/Assembly Bottom")
	)
	(footprint ""
		(layer "F.Cu")
		(at 172.593 -100.294948 -90)
		(property "Reference" "R6012"
			(at 0 0 270)
			(layer "F.SilkS")
			(hide yes)
			(effects
				(font
					(size 1.27 1.27)
				)
			)
		)
		(property "Value" ""
			(at 0 0 270)
			(layer "F.Fab")
			(effects
				(font
					(size 1.27 1.27)
				)
			)
		)
		(duplicate_pad_numbers_are_jumpers no)
		(fp_line
			(start -0.7874 0.4064)
			(end -0.7874 -0.4064)
			(stroke
				(width 0.1524)
				(type default)
			)
			(layer "F.SilkS")
		)
		(fp_line
			(start 0.7874 0.4064)
			(end -0.7874 0.4064)
			(stroke
				(width 0.1524)
				(type default)
			)
			(layer "F.SilkS")
		)
		(fp_line
			(start -0.7874 -0.4064)
			(end 0.7874 -0.4064)
			(stroke
				(width 0.1524)
				(type default)
			)
			(layer "F.SilkS")
		)
		(fp_line
			(start 0.7874 -0.4064)
			(end 0.7874 0.4064)
			(stroke
				(width 0.1524)
				(type default)
			)
			(layer "F.SilkS")
		)
		(fp_line
			(start -0.67945 0.3048)
			(end -0.67945 -0.305054)
			(stroke
				(width 0.1)
				(type default)
			)
			(layer "F.Fab")
		)
		(fp_line
			(start -0.12065 0.3048)
			(end -0.67945 0.3048)
			(stroke
				(width 0.1)
				(type default)
			)
			(layer "F.Fab")
		)
		(fp_line
			(start 0.120396 0.3048)
			(end 0.120396 0.2794)
			(stroke
				(width 0.1)
				(type default)
			)
			(layer "F.Fab")
		)
		(fp_line
			(start 0.67945 0.3048)
			(end 0.120396 0.3048)
			(stroke
				(width 0.1)
				(type default)
			)
			(layer "F.Fab")
		)
		(fp_line
			(start -0.12065 0.2794)
			(end -0.12065 0.3048)
			(stroke
				(width 0.1)
				(type default)
			)
			(layer "F.Fab")
		)
		(fp_line
			(start 0.120396 0.2794)
			(end -0.12065 0.2794)
			(stroke
				(width 0.1)
				(type default)
			)
			(layer "F.Fab")
		)
		(fp_line
			(start -0.12065 -0.2794)
			(end 0.12065 -0.2794)
			(stroke
				(width 0.1)
				(type default)
			)
			(layer "F.Fab")
		)
		(fp_line
			(start 0.12065 -0.2794)
			(end 0.12065 -0.3048)
			(stroke
				(width 0.1)
				(type default)
			)
			(layer "F.Fab")
		)
		(fp_line
			(start 0.12065 -0.3048)
			(end 0.67945 -0.3048)
			(stroke
				(width 0.1)
				(type default)
			)
			(layer "F.Fab")
		)
		(fp_line
			(start 0.67945 -0.3048)
			(end 0.67945 0.3048)
			(stroke
				(width 0.1)
				(type default)
			)
			(layer "F.Fab")
		)
		(fp_line
			(start -0.67945 -0.305054)
			(end -0.12065 -0.305054)
			(stroke
				(width 0.1)
				(type default)
			)
			(layer "F.Fab")
		)
		(fp_line
			(start -0.12065 -0.305054)
			(end -0.12065 -0.2794)
			(stroke
				(width 0.1)
				(type default)
			)
			(layer "F.Fab")
		)
		(pad "1" smd circle
			(at -0.40005 0 270)
			(size 0 0)
			(layers "F.Cu" "F.Mask" "F.Paste")
			(net "SGPIO_SCM_DO_<1>")
		)
		(pad "2" smd circle
			(at 0.40005 0 270)
			(size 0 0)
			(layers "F.Cu" "F.Mask" "F.Paste")
			(net "SGPIO_SCM_DO_R_<1>")
		)
	)
	(footprint ""
		(layer "F.Cu")
		(at 192.688972 -22.694392)
		(property "Reference" "PR4012"
			(at 0 0 0)
			(layer "F.SilkS")
			(hide yes)
			(effects
				(font
					(size 1.27 1.27)
				)
			)
		)
		(property "Value" ""
			(at 0 0 0)
			(layer "F.Fab")
			(effects
				(font
					(size 1.27 1.27)
				)
			)
		)
		(duplicate_pad_numbers_are_jumpers no)
		(fp_line
			(start -0.7874 -0.4064)
			(end 0.7874 -0.4064)
			(stroke
				(width 0.1524)
				(type default)
			)
			(layer "F.SilkS")
		)
		(fp_line
			(start -0.7874 0.4064)
			(end -0.7874 -0.4064)
			(stroke
				(width 0.1524)
				(type default)
			)
			(layer "F.SilkS")
		)
		(fp_line
			(start 0.7874 -0.4064)
			(end 0.7874 0.4064)
			(stroke
				(width 0.1524)
				(type default)
			)
			(layer "F.SilkS")
		)
		(fp_line
			(start 0.7874 0.4064)
			(end -0.7874 0.4064)
			(stroke
				(width 0.1524)
				(type default)
			)
			(layer "F.SilkS")
		)
		(fp_line
			(start -0.67945 -0.305054)
			(end -0.12065 -0.305054)
			(stroke
				(width 0.1)
				(type default)
			)
			(layer "F.Fab")
		)
		(fp_line
			(start -0.67945 0.3048)
			(end -0.67945 -0.305054)
			(stroke
				(width 0.1)
				(type default)
			)
			(layer "F.Fab")
		)
		(fp_line
			(start -0.12065 -0.305054)
			(end -0.12065 -0.2794)
			(stroke
				(width 0.1)
				(type default)
			)
			(layer "F.Fab")
		)
		(fp_line
			(start -0.12065 -0.2794)
			(end 0.12065 -0.2794)
			(stroke
				(width 0.1)
				(type default)
			)
			(layer "F.Fab")
		)
		(fp_line
			(start -0.12065 0.2794)
			(end -0.12065 0.3048)
			(stroke
				(width 0.1)
				(type default)
			)
			(layer "F.Fab")
		)
		(fp_line
			(start -0.12065 0.3048)
			(end -0.67945 0.3048)
			(stroke
				(width 0.1)
				(type default)
			)
			(layer "F.Fab")
		)
		(fp_line
			(start 0.120396 0.2794)
			(end -0.12065 0.2794)
			(stroke
				(width 0.1)
				(type default)
			)
			(layer "F.Fab")
		)
		(fp_line
			(start 0.120396 0.3048)
			(end 0.120396 0.2794)
			(stroke
				(width 0.1)
				(type default)
			)
			(layer "F.Fab")
		)
		(fp_line
			(start 0.12065 -0.3048)
			(end 0.67945 -0.3048)
			(stroke
				(width 0.1)
				(type default)
			)
			(layer "F.Fab")
		)
		(fp_line
			(start 0.12065 -0.2794)
			(end 0.12065 -0.3048)
			(stroke
				(width 0.1)
				(type default)
			)
			(layer "F.Fab")
		)
		(fp_line
			(start 0.67945 -0.3048)
			(end 0.67945 0.3048)
			(stroke
				(width 0.1)
				(type default)
			)
			(layer "F.Fab")
		)
		(fp_line
			(start 0.67945 0.3048)
			(end 0.120396 0.3048)
			(stroke
				(width 0.1)
				(type default)
			)
			(layer "F.Fab")
		)
		(pad "1" smd circle
			(at -0.40005 0)
			(size 0 0)
			(layers "F.Cu" "F.Mask" "F.Paste")
			(net "P12V_SCM_PWRGD")
		)
		(pad "2" smd circle
			(at 0.40005 0)
			(size 0 0)
			(layers "F.Cu" "F.Mask" "F.Paste")
			(net "HP_LVC3_SCM_HSC_PWRGD")
		)
	)
)
